# S9S_MB_2U (Grand Teton) — schematic netlist excerpt (pin names and nets, part order shuffled) for the footprints in the layout excerpt that follows; sources: Cadence DE-HDL packaged netlist, KiCad conversion of 03242023_DA0F0TMBIJ0_F0T_Motherboard_J_brd_V01_OCP.brd

PR258  Q_RES  28K 1% EMPTY  pkg 0402LF  page 292 : A = PVCCINFAON_CPU1_VREF ; B = PVCCINFAON_CPU1_ADDR
PC609_P0_2  Q_CAP  22UF 16V 20% X6S  pkg C0805  page 271 : A = SW_P12V_PVCCFA_EHV_FIVRA_CPU0_L ; B = GND
R266  Q_RES  240 1% EMPTY  pkg 0402LF  page 119 : A = PVNN_TERM_CPU1 ; B = PU_CPU1_SOCKET_ID1

(kicad_pcb
	(version 20260206)
	(generator "pcbnew")
	(generator_version "10.0")
	(general
		(thickness 1.6)
		(legacy_teardrops no)
	)
	(paper "A4")
	(title_block
		(title "03242023_DA0F0TMBIJ0_F0T_Motherboard_J_brd_V01_OCP.brd")
		(comment 1 "Grand Teton / footprints 4888-4890 of 6105")
	)
	(layers
		(0 "F.Cu" signal "TOP")
		(4 "In1.Cu" signal "GND")
		(6 "In2.Cu" signal "IN1")
		(8 "In3.Cu" signal "GND1")
		(10 "In4.Cu" signal "IN2")
		(12 "In5.Cu" signal "GND2")
		(14 "In6.Cu" signal "IN3")
		(16 "In7.Cu" signal "GND3")
		(18 "In8.Cu" signal "VCC")
		(20 "In9.Cu" signal "VCC1")
		(22 "In10.Cu" signal "GND4")
		(24 "In11.Cu" signal "IN4")
		(26 "In12.Cu" signal "GND5")
		(28 "In13.Cu" signal "IN5")
		(30 "In14.Cu" signal "GND6")
		(32 "In15.Cu" signal "IN6")
		(34 "In16.Cu" signal "GND7")
		(2 "B.Cu" signal "BOTTOM")
		(9 "F.Adhes" user "F.Adhesive")
		(11 "B.Adhes" user "B.Adhesive")
		(13 "F.Paste" user "Package Geometry/Pastemask Top")
		(15 "B.Paste" user "Package Geometry/Pastemask Bottom")
		(5 "F.SilkS" user "Ref Des/Silkscreen Top")
		(7 "B.SilkS" user "Ref Des/Silkscreen Bottom")
		(1 "F.Mask" user "Board Geometry/Soldermask Top")
		(3 "B.Mask" user "Board Geometry/Soldermask Bottom")
		(17 "Dwgs.User" user "User.Drawings")
		(19 "Cmts.User" user "User.Comments")
		(21 "Eco1.User" user "User.Eco1")
		(23 "Eco2.User" user "User.Eco2")
		(25 "Edge.Cuts" user "Board Geometry/Outline")
		(27 "Margin" user)
		(31 "F.CrtYd" user "Package Geometry/Place Bound Top")
		(29 "B.CrtYd" user "Package Geometry/Place Bound Bottom")
		(35 "F.Fab" user "Ref Des/Assembly Top")
		(33 "B.Fab" user "Ref Des/Assembly Bottom")
	)
	(footprint ""
		(layer "B.Cu")
		(at 177.123344 -192.699894 -90)
		(property "Reference" "R266"
			(at 0 0 90)
			(layer "B.SilkS")
			(hide yes)
			(effects
				(font
					(size 1.27 1.27)
				)
				(justify mirror)
			)
		)
		(property "Value" ""
			(at 0 0 90)
			(layer "B.Fab")
			(effects
				(font
					(size 1.27 1.27)
				)
				(justify mirror)
			)
		)
		(duplicate_pad_numbers_are_jumpers no)
		(fp_line
			(start -0.7874 0.4064)
			(end 0.7874 0.4064)
			(stroke
				(width 0.1524)
				(type default)
			)
			(layer "B.SilkS")
		)
		(fp_line
			(start 0.7874 0.4064)
			(end 0.7874 -0.4064)
			(stroke
				(width 0.1524)
				(type default)
			)
			(layer "B.SilkS")
		)
		(fp_line
			(start -0.7874 -0.4064)
			(end -0.7874 0.4064)
			(stroke
				(width 0.1524)
				(type default)
			)
			(layer "B.SilkS")
		)
		(fp_line
			(start 0.7874 -0.4064)
			(end -0.7874 -0.4064)
			(stroke
				(width 0.1524)
				(type default)
			)
			(layer "B.SilkS")
		)
		(fp_line
			(start -0.67945 0.3048)
			(end -0.120396 0.3048)
			(stroke
				(width 0.1)
				(type default)
			)
			(layer "B.Fab")
		)
		(fp_line
			(start -0.120396 0.3048)
			(end -0.120396 0.2794)
			(stroke
				(width 0.1)
				(type default)
			)
			(layer "B.Fab")
		)
		(fp_line
			(start 0.12065 0.3048)
			(end 0.67945 0.3048)
			(stroke
				(width 0.1)
				(type default)
			)
			(layer "B.Fab")
		)
		(fp_line
			(start 0.67945 0.3048)
			(end 0.67945 -0.305054)
			(stroke
				(width 0.1)
				(type default)
			)
			(layer "B.Fab")
		)
		(fp_line
			(start -0.120396 0.2794)
			(end 0.12065 0.2794)
			(stroke
				(width 0.1)
				(type default)
			)
			(layer "B.Fab")
		)
		(fp_line
			(start 0.12065 0.2794)
			(end 0.12065 0.3048)
			(stroke
				(width 0.1)
				(type default)
			)
			(layer "B.Fab")
		)
		(fp_line
			(start -0.12065 -0.2794)
			(end -0.12065 -0.3048)
			(stroke
				(width 0.1)
				(type default)
			)
			(layer "B.Fab")
		)
		(fp_line
			(start 0.12065 -0.2794)
			(end -0.12065 -0.2794)
			(stroke
				(width 0.1)
				(type default)
			)
			(layer "B.Fab")
		)
		(fp_line
			(start -0.67945 -0.3048)
			(end -0.67945 0.3048)
			(stroke
				(width 0.1)
				(type default)
			)
			(layer "B.Fab")
		)
		(fp_line
			(start -0.12065 -0.3048)
			(end -0.67945 -0.3048)
			(stroke
				(width 0.1)
				(type default)
			)
			(layer "B.Fab")
		)
		(fp_line
			(start 0.12065 -0.305054)
			(end 0.12065 -0.2794)
			(stroke
				(width 0.1)
				(type default)
			)
			(layer "B.Fab")
		)
		(fp_line
			(start 0.67945 -0.305054)
			(end 0.12065 -0.305054)
			(stroke
				(width 0.1)
				(type default)
			)
			(layer "B.Fab")
		)
		(pad "1" smd circle
			(at 0.40005 0 90)
			(size 0 0)
			(layers "B.Cu" "B.Mask" "B.Paste")
			(net "PVNN_TERM_CPU1")
		)
		(pad "2" smd circle
			(at -0.40005 0 90)
			(size 0 0)
			(layers "B.Cu" "B.Mask" "B.Paste")
			(net "PU_CPU1_SOCKET_ID1")
		)
	)
	(footprint ""
		(layer "B.Cu")
		(at 299.596048 -362.795058 90)
		(property "Reference" "PC609_P0_2"
			(at 0 0 90)
			(layer "B.SilkS")
			(hide yes)
			(effects
				(font
					(size 1.27 1.27)
				)
				(justify mirror)
			)
		)
		(property "Value" ""
			(at 0 0 90)
			(layer "B.Fab")
			(effects
				(font
					(size 1.27 1.27)
				)
				(justify mirror)
			)
		)
		(duplicate_pad_numbers_are_jumpers no)
		(fp_line
			(start 1.524 -0.762)
			(end -1.524 -0.762)
			(stroke
				(width 0.1524)
				(type default)
			)
			(layer "B.SilkS")
		)
		(fp_line
			(start -1.524 -0.762)
			(end -1.524 0.762)
			(stroke
				(width 0.1524)
				(type default)
			)
			(layer "B.SilkS")
		)
		(fp_line
			(start 1.524 0.762)
			(end 1.524 -0.762)
			(stroke
				(width 0.1524)
				(type default)
			)
			(layer "B.SilkS")
		)
		(fp_line
			(start -1.524 0.762)
			(end 1.524 0.762)
			(stroke
				(width 0.1524)
				(type default)
			)
			(layer "B.SilkS")
		)
		(fp_line
			(start 1.1049 -0.724916)
			(end 1.1049 0.724916)
			(stroke
				(width 0.1)
				(type default)
			)
			(layer "B.Fab")
		)
		(fp_line
			(start -1.1049 -0.724916)
			(end 1.1049 -0.724916)
			(stroke
				(width 0.1)
				(type default)
			)
			(layer "B.Fab")
		)
		(fp_line
			(start 1.1049 0.724916)
			(end -1.1049 0.724916)
			(stroke
				(width 0.1)
				(type default)
			)
			(layer "B.Fab")
		)
		(fp_line
			(start -1.1049 0.724916)
			(end -1.1049 -0.724916)
			(stroke
				(width 0.1)
				(type default)
			)
			(layer "B.Fab")
		)
		(pad "1" smd rect
			(at 0.889 0 90)
			(size 1.016 1.27)
			(layers "B.Cu" "B.Mask" "B.Paste")
			(net "SW_P12V_PVCCFA_EHV_FIVRA_CPU0_L")
		)
		(pad "2" smd rect
			(at -0.889 0 90)
			(size 1.016 1.27)
			(layers "B.Cu" "B.Mask" "B.Paste")
			(net "GND")
		)
	)
	(footprint ""
		(layer "B.Cu")
		(at 27.0383 -131.55295 180)
		(property "Reference" "PR258"
			(at 0 0 0)
			(layer "B.SilkS")
			(hide yes)
			(effects
				(font
					(size 1.27 1.27)
				)
				(justify mirror)
			)
		)
		(property "Value" ""
			(at 0 0 0)
			(layer "B.Fab")
			(effects
				(font
					(size 1.27 1.27)
				)
				(justify mirror)
			)
		)
		(duplicate_pad_numbers_are_jumpers no)
		(fp_line
			(start 0.7874 0.4064)
			(end 0.7874 -0.4064)
			(stroke
				(width 0.1524)
				(type default)
			)
			(layer "B.SilkS")
		)
		(fp_line
			(start 0.7874 -0.4064)
			(end -0.7874 -0.4064)
			(stroke
				(width 0.1524)
				(type default)
			)
			(layer "B.SilkS")
		)
		(fp_line
			(start -0.7874 0.4064)
			(end 0.7874 0.4064)
			(stroke
				(width 0.1524)
				(type default)
			)
			(layer "B.SilkS")
		)
		(fp_line
			(start -0.7874 -0.4064)
			(end -0.7874 0.4064)
			(stroke
				(width 0.1524)
				(type default)
			)
			(layer "B.SilkS")
		)
		(fp_line
			(start 0.67945 0.3048)
			(end 0.67945 -0.305054)
			(stroke
				(width 0.1)
				(type default)
			)
			(layer "B.Fab")
		)
		(fp_line
			(start 0.67945 -0.305054)
			(end 0.12065 -0.305054)
			(stroke
				(width 0.1)
				(type default)
			)
			(layer "B.Fab")
		)
		(fp_line
			(start 0.12065 0.3048)
			(end 0.67945 0.3048)
			(stroke
				(width 0.1)
				(type default)
			)
			(layer "B.Fab")
		)
		(fp_line
			(start 0.12065 0.2794)
			(end 0.12065 0.3048)
			(stroke
				(width 0.1)
				(type default)
			)
			(layer "B.Fab")
		)
		(fp_line
			(start 0.12065 -0.2794)
			(end -0.12065 -0.2794)
			(stroke
				(width 0.1)
				(type default)
			)
			(layer "B.Fab")
		)
		(fp_line
			(start 0.12065 -0.305054)
			(end 0.12065 -0.2794)
			(stroke
				(width 0.1)
				(type default)
			)
			(layer "B.Fab")
		)
		(fp_line
			(start -0.120396 0.3048)
			(end -0.120396 0.2794)
			(stroke
				(width 0.1)
				(type default)
			)
			(layer "B.Fab")
		)
		(fp_line
			(start -0.120396 0.2794)
			(end 0.12065 0.2794)
			(stroke
				(width 0.1)
				(type default)
			)
			(layer "B.Fab")
		)
		(fp_line
			(start -0.12065 -0.2794)
			(end -0.12065 -0.3048)
			(stroke
				(width 0.1)
				(type default)
			)
			(layer "B.Fab")
		)
		(fp_line
			(start -0.12065 -0.3048)
			(end -0.67945 -0.3048)
			(stroke
				(width 0.1)
				(type default)
			)
			(layer "B.Fab")
		)
		(fp_line
			(start -0.67945 0.3048)
			(end -0.120396 0.3048)
			(stroke
				(width 0.1)
				(type default)
			)
			(layer "B.Fab")
		)
		(fp_line
			(start -0.67945 -0.3048)
			(end -0.67945 0.3048)
			(stroke
				(width 0.1)
				(type default)
			)
			(layer "B.Fab")
		)
		(pad "1" smd circle
			(at 0.40005 0)
			(size 0 0)
			(layers "B.Cu" "B.Mask" "B.Paste")
			(net "PVCCINFAON_CPU1_VREF")
		)
		(pad "2" smd circle
			(at -0.40005 0)
			(size 0 0)
			(layers "B.Cu" "B.Mask" "B.Paste")
			(net "PVCCINFAON_CPU1_ADDR")
		)
	)
)
